(kicad_pcb
	(version 20260206)
	(generator "pcbnew")
	(generator_version "10.0")
	(general
		(thickness 1.6)
		(legacy_teardrops no)
	)
	(paper "A4")
	(title_block
		(title "v2-tray-backplane — ms_tbp_v2.brd")
		(comment 1 "Open CloudServer (Microsoft) / footprints 96-98 of 164")
	)
	(layers
		(0 "F.Cu" signal "TOP")
		(4 "In1.Cu" signal "LYR2")
		(6 "In2.Cu" signal "LYR3")
		(8 "In3.Cu" signal "LYR4")
		(10 "In4.Cu" signal "LYR5")
		(12 "In5.Cu" signal "LYR6")
		(14 "In6.Cu" signal "LYR7")
		(2 "B.Cu" signal "BOTTOM")
		(9 "F.Adhes" user "F.Adhesive")
		(11 "B.Adhes" user "B.Adhesive")
		(13 "F.Paste" user "Package Geometry/Pastemask Top")
		(15 "B.Paste" user "Package Geometry/Pastemask Bottom")
		(5 "F.SilkS" user "Ref Des/Silkscreen Top")
		(7 "B.SilkS" user "Ref Des/Silkscreen Bottom")
		(1 "F.Mask" user "Board Geometry/Soldermask Top")
		(3 "B.Mask" user "Board Geometry/Soldermask Bottom")
		(17 "Dwgs.User" user "User.Drawings")
		(19 "Cmts.User" user "User.Comments")
		(21 "Eco1.User" user "User.Eco1")
		(23 "Eco2.User" user "User.Eco2")
		(25 "Edge.Cuts" user "Board Geometry/Outline")
		(27 "Margin" user)
		(31 "F.CrtYd" user "Package Geometry/Place Bound Top")
		(29 "B.CrtYd" user "Package Geometry/Place Bound Bottom")
		(35 "F.Fab" user "Ref Des/Assembly Top")
		(33 "B.Fab" user "Ref Des/Assembly Bottom")
	)
	(footprint ""
		(layer "F.Cu")
		(at -296.145801 5.524602 180)
		(property "Reference" "R23"
			(at -3.052661 -0.309778 0)
			(unlocked yes)
			(layer "F.SilkS")
			(effects
				(font
					(size 0.762 0.5334)
					(thickness 0.1016)
				)
			)
		)
		(property "Value" ""
			(at 0 0 180)
			(layer "F.Fab")
			(effects
				(font
					(size 1.27 1.27)
				)
			)
		)
		(duplicate_pad_numbers_are_jumpers no)
		(fp_line
			(start 0 -0.381)
			(end 0 0.381)
			(stroke
				(width 0.127)
				(type default)
			)
			(layer "F.SilkS")
		)
		(fp_poly
			(pts
				(xy 1.255601 0.6564) (xy -1.255601 0.6564) (xy -1.255601 -0.656399) (xy 1.255601 -0.656399)
			)
			(stroke
				(width 0)
				(type default)
			)
			(fill no)
			(layer "F.CrtYd")
		)
		(fp_line
			(start 0.800001 0.4)
			(end 0.800001 -0.399999)
			(stroke
				(width 0.1)
				(type default)
			)
			(layer "F.Fab")
		)
		(fp_line
			(start 0.800001 -0.399999)
			(end -0.800001 -0.399999)
			(stroke
				(width 0.1)
				(type default)
			)
			(layer "F.Fab")
		)
		(fp_line
			(start -0.800001 0.4)
			(end 0.800001 0.4)
			(stroke
				(width 0.1)
				(type default)
			)
			(layer "F.Fab")
		)
		(fp_line
			(start -0.800001 -0.399999)
			(end -0.800001 0.4)
			(stroke
				(width 0.1)
				(type default)
			)
			(layer "F.Fab")
		)
		(pad "1" smd rect
			(at -0.650001 0 180)
			(size 0.7112 0.8128)
			(layers "F.Cu" "F.Mask" "F.Paste")
			(net "ETH10G_B1_RS0")
		)
		(pad "2" smd rect
			(at 0.650001 0)
			(size 0.7112 0.8128)
			(layers "F.Cu" "F.Mask" "F.Paste")
			(net "GND")
		)
	)
	(footprint ""
		(layer "F.Cu")
		(at -294.040001 45.360001 180)
		(property "Reference" "J7"
			(at 7.584999 17.000901 0)
			(unlocked yes)
			(layer "F.SilkS")
			(effects
				(font
					(size 0.762 0.5334)
					(thickness 0.1016)
				)
			)
		)
		(property "Value" ""
			(at 0 0 180)
			(layer "F.Fab")
			(effects
				(font
					(size 1.27 1.27)
				)
			)
		)
		(duplicate_pad_numbers_are_jumpers no)
		(fp_line
			(start 10.950001 15.3)
			(end -0.95 15.3)
			(stroke
				(width 0.127)
				(type default)
			)
			(layer "F.SilkS")
		)
		(fp_line
			(start 10.950001 5.609001)
			(end 10.950001 15.3)
			(stroke
				(width 0.127)
				(type default)
			)
			(layer "F.SilkS")
		)
		(fp_line
			(start 10.950001 -11.999999)
			(end 10.950001 4.212001)
			(stroke
				(width 0.127)
				(type default)
			)
			(layer "F.SilkS")
		)
		(fp_line
			(start -0.95 15.3)
			(end -0.95 13.356001)
			(stroke
				(width 0.127)
				(type default)
			)
			(layer "F.SilkS")
		)
		(fp_line
			(start -0.95 11.451001)
			(end -0.95 2.561001)
			(stroke
				(width 0.127)
				(type default)
			)
			(layer "F.SilkS")
		)
		(fp_line
			(start -0.95 0.656001)
			(end -0.95 -11.999999)
			(stroke
				(width 0.127)
				(type default)
			)
			(layer "F.SilkS")
		)
		(fp_line
			(start -0.95 -11.999999)
			(end 10.950001 -11.999999)
			(stroke
				(width 0.127)
				(type default)
			)
			(layer "F.SilkS")
		)
		(fp_poly
			(pts
				(arc
					(start -4.93 12.500001)
					(mid -3.486036 15.986037)
					(end 0 17.430001)
				)
				(arc
					(start 10.000001 17.430001)
					(mid 13.486037 15.986037)
					(end 14.930001 12.500001)
				)
				(arc
					(start 14.930001 -0.1)
					(mid 13.486037 -3.586036)
					(end 10.000001 -5.03)
				)
				(arc
					(start 0 -5.03)
					(mid -3.486036 -3.586036)
					(end -4.93 -0.1)
				)
			)
			(stroke
				(width 0)
				(type default)
			)
			(fill no)
			(layer "B.CrtYd")
		)
		(fp_poly
			(pts
				(xy 11.949999 16.300001) (xy -1.950001 16.300001) (xy -1.950001 -12.999999) (xy 11.949999 -12.999999)
			)
			(stroke
				(width 0)
				(type default)
			)
			(fill no)
			(layer "F.CrtYd")
		)
		(fp_line
			(start 10.950001 15.3)
			(end -0.95 15.3)
			(stroke
				(width 0.1)
				(type default)
			)
			(layer "F.Fab")
		)
		(fp_line
			(start 10.950001 -11.999999)
			(end 10.950001 15.3)
			(stroke
				(width 0.1)
				(type default)
			)
			(layer "F.Fab")
		)
		(fp_line
			(start -0.95 15.3)
			(end -0.95 -11.999999)
			(stroke
				(width 0.1)
				(type default)
			)
			(layer "F.Fab")
		)
		(fp_line
			(start -0.95 -11.999999)
			(end 10.950001 -11.999999)
			(stroke
				(width 0.1)
				(type default)
			)
			(layer "F.Fab")
		)
		(fp_text user "*"
			(at -2.067001 -1.204549 0)
			(unlocked yes)
			(layer "F.SilkS")
			(effects
				(font
					(size 0.381 0.381)
					(thickness 0.381)
				)
			)
		)
		(fp_text user "A1"
			(at -2.321001 0.109901 0)
			(unlocked yes)
			(layer "F.SilkS")
			(effects
				(font
					(size 0.762 0.5334)
					(thickness 0.1016)
				)
			)
		)
		(fp_text user "I6"
			(at 11.423 10.9539 0)
			(unlocked yes)
			(layer "B.SilkS")
			(effects
				(font
					(size 0.762 0.5334)
					(thickness 0.1016)
				)
				(justify mirror)
			)
		)
		(fp_text user "A6"
			(at 11.423 -0.2461 0)
			(unlocked yes)
			(layer "B.SilkS")
			(effects
				(font
					(size 0.762 0.5334)
					(thickness 0.1016)
				)
				(justify mirror)
			)
		)
		(fp_text user "E6"
			(at 11.267999 5.189901 0)
			(unlocked yes)
			(layer "B.SilkS")
			(effects
				(font
					(size 0.762 0.5334)
					(thickness 0.1016)
				)
				(justify mirror)
			)
		)
		(fp_text user "I1"
			(at -1.289761 11.273201 0)
			(unlocked yes)
			(layer "B.SilkS")
			(effects
				(font
					(size 0.762 0.5334)
					(thickness 0.1016)
				)
				(justify mirror)
			)
		)
		(fp_text user "E1"
			(at -1.289761 5.923961 0)
			(unlocked yes)
			(layer "B.SilkS")
			(effects
				(font
					(size 0.762 0.5334)
					(thickness 0.1016)
				)
				(justify mirror)
			)
		)
		(fp_text user "A1"
			(at -1.295999 -0.1191 0)
			(unlocked yes)
			(layer "B.SilkS")
			(effects
				(font
					(size 0.762 0.5334)
					(thickness 0.1016)
				)
				(justify mirror)
			)
		)
		(pad "A1" thru_hole circle
			(at 0 0 180)
			(size 0.8128 0.8128)
			(drill 0.508)
			(layers "*.Cu" "*.Mask")
			(remove_unused_layers no)
			(net "ETH40G_B1_TX3P")
		)
		(pad "A2" thru_hole circle
			(at 2.000001 -0.1 180)
			(size 0.8128 0.8128)
			(drill 0.508)
			(layers "*.Cu" "*.Mask")
			(remove_unused_layers no)
			(net "GND")
		)
		(pad "A3" thru_hole circle
			(at 4 0 180)
			(size 0.8128 0.8128)
			(drill 0.508)
			(layers "*.Cu" "*.Mask")
			(remove_unused_layers no)
			(net "ETH40G_B1_RX2P")
		)
		(pad "A4" thru_hole circle
			(at 6.000001 -0.1 180)
			(size 0.8128 0.8128)
			(drill 0.508)
			(layers "*.Cu" "*.Mask")
			(remove_unused_layers no)
			(net "GND")
		)
		(pad "A5" thru_hole circle
			(at 7.999999 0 180)
			(size 0.8128 0.8128)
			(drill 0.508)
			(layers "*.Cu" "*.Mask")
			(remove_unused_layers no)
			(net "ETH40G_B1_RX1P")
		)
		(pad "A6" thru_hole circle
			(at 10 -0.1 180)
			(size 0.8128 0.8128)
			(drill 0.508)
			(layers "*.Cu" "*.Mask")
			(remove_unused_layers no)
			(net "GND")
		)
		(pad "B1" thru_hole circle
			(at 0 1.4 180)
			(size 0.8128 0.8128)
			(drill 0.508)
			(layers "*.Cu" "*.Mask")
			(remove_unused_layers no)
			(net "ETH40G_B1_TX3N")
		)
		(pad "B2" thru_hole circle
			(at 2.000001 1.3 180)
			(size 0.8128 0.8128)
			(drill 0.508)
			(layers "*.Cu" "*.Mask")
			(remove_unused_layers no)
			(net "ETH40G_B1_RX3P")
		)
		(pad "B3" thru_hole circle
			(at 4 1.4 180)
			(size 0.8128 0.8128)
			(drill 0.508)
			(layers "*.Cu" "*.Mask")
			(remove_unused_layers no)
			(net "ETH40G_B1_RX2N")
		)
		(pad "B4" thru_hole circle
			(at 6.000001 1.3 180)
			(size 0.8128 0.8128)
			(drill 0.508)
			(layers "*.Cu" "*.Mask")
			(remove_unused_layers no)
			(net "ETH40G_B1_TX2P")
		)
		(pad "B5" thru_hole circle
			(at 7.999999 1.4 180)
			(size 0.8128 0.8128)
			(drill 0.508)
			(layers "*.Cu" "*.Mask")
			(remove_unused_layers no)
			(net "ETH40G_B1_RX1N")
		)
		(pad "B6" thru_hole circle
			(at 10 1.3 180)
			(size 0.8128 0.8128)
			(drill 0.508)
			(layers "*.Cu" "*.Mask")
			(remove_unused_layers no)
			(net "ETH40G_B1_TX1P")
		)
		(pad "C1" thru_hole circle
			(at 0 2.799999 180)
			(size 0.8128 0.8128)
			(drill 0.508)
			(layers "*.Cu" "*.Mask")
			(remove_unused_layers no)
			(net "GND")
		)
		(pad "C2" thru_hole circle
			(at 2.000001 2.7 180)
			(size 0.8128 0.8128)
			(drill 0.508)
			(layers "*.Cu" "*.Mask")
			(remove_unused_layers no)
			(net "ETH40G_B1_RX3N")
		)
		(pad "C3" thru_hole circle
			(at 4 2.799999 180)
			(size 0.8128 0.8128)
			(drill 0.508)
			(layers "*.Cu" "*.Mask")
			(remove_unused_layers no)
			(net "GND")
		)
		(pad "C4" thru_hole circle
			(at 6.000001 2.7 180)
			(size 0.8128 0.8128)
			(drill 0.508)
			(layers "*.Cu" "*.Mask")
			(remove_unused_layers no)
			(net "ETH40G_B1_TX2N")
		)
		(pad "C5" thru_hole circle
			(at 7.999999 2.799999 180)
			(size 0.8128 0.8128)
			(drill 0.508)
			(layers "*.Cu" "*.Mask")
			(remove_unused_layers no)
			(net "GND")
		)
		(pad "C6" thru_hole circle
			(at 10 2.7 180)
			(size 0.8128 0.8128)
			(drill 0.508)
			(layers "*.Cu" "*.Mask")
			(remove_unused_layers no)
			(net "ETH40G_B1_TX1N")
		)
		(pad "D1" thru_hole circle
			(at 0 4.199999 180)
			(size 0.8128 0.8128)
			(drill 0.508)
			(layers "*.Cu" "*.Mask")
			(remove_unused_layers no)
			(net "ETH10G_B1_RXP")
		)
		(pad "D2" thru_hole circle
			(at 2.000001 4.099999 180)
			(size 0.8128 0.8128)
			(drill 0.508)
			(layers "*.Cu" "*.Mask")
			(remove_unused_layers no)
			(net "GND")
		)
		(pad "D3" thru_hole circle
			(at 4 4.199999 180)
			(size 0.8128 0.8128)
			(drill 0.508)
			(layers "*.Cu" "*.Mask")
			(remove_unused_layers no)
			(net "ETH10G_B1_SDA")
		)
		(pad "D4" thru_hole circle
			(at 6.000001 4.099999 180)
			(size 0.8128 0.8128)
			(drill 0.508)
			(layers "*.Cu" "*.Mask")
			(remove_unused_layers no)
			(net "GND")
		)
		(pad "D5" thru_hole circle
			(at 7.999999 4.199999 180)
			(size 0.8128 0.8128)
			(drill 0.508)
			(layers "*.Cu" "*.Mask")
			(remove_unused_layers no)
			(net "P3V3_B1_QSFP")
		)
		(pad "D6" thru_hole circle
			(at 10 4.099999 180)
			(size 0.8128 0.8128)
			(drill 0.508)
			(layers "*.Cu" "*.Mask")
			(remove_unused_layers no)
			(net "GND")
		)
		(pad "E1" thru_hole circle
			(at 0 5.599999 180)
			(size 0.8128 0.8128)
			(drill 0.508)
			(layers "*.Cu" "*.Mask")
			(remove_unused_layers no)
			(net "ETH10G_B1_RXN")
		)
		(pad "E2" thru_hole circle
			(at 2.000001 5.499999 180)
			(size 0.8128 0.8128)
			(drill 0.508)
			(layers "*.Cu" "*.Mask")
			(remove_unused_layers no)
			(net "Net_15")
		)
		(pad "E3" thru_hole circle
			(at 4 5.599999 180)
			(size 0.8128 0.8128)
			(drill 0.508)
			(layers "*.Cu" "*.Mask")
			(remove_unused_layers no)
			(net "ETH10G_B1_SCL")
		)
		(pad "E4" thru_hole circle
			(at 6.000001 5.499999 180)
			(size 0.8128 0.8128)
			(drill 0.508)
			(layers "*.Cu" "*.Mask")
			(remove_unused_layers no)
			(net "ETH40G_B1_SDA")
		)
		(pad "E5" thru_hole circle
			(at 7.999999 5.599999 180)
			(size 0.8128 0.8128)
			(drill 0.508)
			(layers "*.Cu" "*.Mask")
			(remove_unused_layers no)
			(net "P3V3_B1_QSFP")
		)
		(pad "E6" thru_hole circle
			(at 10 5.499999 180)
			(size 0.8128 0.8128)
			(drill 0.508)
			(layers "*.Cu" "*.Mask")
			(remove_unused_layers no)
			(net "ETH40G_B1_RX0P")
		)
		(pad "F1" thru_hole circle
			(at 0 7.000001 180)
			(size 0.8128 0.8128)
			(drill 0.508)
			(layers "*.Cu" "*.Mask")
			(remove_unused_layers no)
			(net "GND")
		)
		(pad "F2" thru_hole circle
			(at 2.000001 6.899999 180)
			(size 0.8128 0.8128)
			(drill 0.508)
			(layers "*.Cu" "*.Mask")
			(remove_unused_layers no)
			(net "SKU_B1_ID2")
		)
		(pad "F3" thru_hole circle
			(at 4 7.000001 180)
			(size 0.8128 0.8128)
			(drill 0.508)
			(layers "*.Cu" "*.Mask")
			(remove_unused_layers no)
			(net "SKU_B1_ID0")
		)
		(pad "F4" thru_hole circle
			(at 6.000001 6.899999 180)
			(size 0.8128 0.8128)
			(drill 0.508)
			(layers "*.Cu" "*.Mask")
			(remove_unused_layers no)
			(net "ETH40G_B1_SCL")
		)
		(pad "F5" thru_hole circle
			(at 7.999999 7.000001 180)
			(size 0.8128 0.8128)
			(drill 0.508)
			(layers "*.Cu" "*.Mask")
			(remove_unused_layers no)
			(net "GND")
		)
		(pad "F6" thru_hole circle
			(at 10 6.899999 180)
			(size 0.8128 0.8128)
			(drill 0.508)
			(layers "*.Cu" "*.Mask")
			(remove_unused_layers no)
			(net "ETH40G_B1_RX0N")
		)
		(pad "G1" thru_hole circle
			(at 0 8.400001 180)
			(size 0.8128 0.8128)
			(drill 0.508)
			(layers "*.Cu" "*.Mask")
			(remove_unused_layers no)
			(net "ETH10G_B1_TXP")
		)
		(pad "G2" thru_hole circle
			(at 2.000001 8.300001 180)
			(size 0.8128 0.8128)
			(drill 0.508)
			(layers "*.Cu" "*.Mask")
			(remove_unused_layers no)
			(net "GND")
		)
		(pad "G3" thru_hole circle
			(at 4 8.400001 180)
			(size 0.8128 0.8128)
			(drill 0.508)
			(layers "*.Cu" "*.Mask")
			(remove_unused_layers no)
			(net "SERIAL_B1_RX1")
		)
		(pad "G4" thru_hole circle
			(at 6.000001 8.300001 180)
			(size 0.8128 0.8128)
			(drill 0.508)
			(layers "*.Cu" "*.Mask")
			(remove_unused_layers no)
			(net "SERIAL_B1_RX2")
		)
		(pad "G5" thru_hole circle
			(at 7.999999 8.400001 180)
			(size 0.8128 0.8128)
			(drill 0.508)
			(layers "*.Cu" "*.Mask")
			(remove_unused_layers no)
			(net "PSU_B1_ALERT_N")
		)
		(pad "G6" thru_hole circle
			(at 10 8.300001 180)
			(size 0.8128 0.8128)
			(drill 0.508)
			(layers "*.Cu" "*.Mask")
			(remove_unused_layers no)
			(net "GND")
		)
		(pad "H1" thru_hole circle
			(at 0 9.800001 180)
			(size 0.8128 0.8128)
			(drill 0.508)
			(layers "*.Cu" "*.Mask")
			(remove_unused_layers no)
			(net "ETH10G_B1_TXN")
		)
		(pad "H2" thru_hole circle
			(at 2.000001 9.700001 180)
			(size 0.8128 0.8128)
			(drill 0.508)
			(layers "*.Cu" "*.Mask")
			(remove_unused_layers no)
			(net "BLADE_B1_EN1")
		)
		(pad "H3" thru_hole circle
			(at 4 9.800001 180)
			(size 0.8128 0.8128)
			(drill 0.508)
			(layers "*.Cu" "*.Mask")
			(remove_unused_layers no)
			(net "SERIAL_B1_TX1")
		)
		(pad "H4" thru_hole circle
			(at 6.000001 9.700001 180)
			(size 0.8128 0.8128)
			(drill 0.508)
			(layers "*.Cu" "*.Mask")
			(remove_unused_layers no)
			(net "SERIAL_B1_TX2")
		)
		(pad "H5" thru_hole circle
			(at 7.999999 9.800001 180)
			(size 0.8128 0.8128)
			(drill 0.508)
			(layers "*.Cu" "*.Mask")
			(remove_unused_layers no)
			(net "ETH40G_B1_PRES_N")
		)
		(pad "H6" thru_hole circle
			(at 10 9.700001 180)
			(size 0.8128 0.8128)
			(drill 0.508)
			(layers "*.Cu" "*.Mask")
			(remove_unused_layers no)
			(net "ETH40G_B1_TX0P")
		)
		(pad "I1" thru_hole circle
			(at 0 11.2 180)
			(size 0.8128 0.8128)
			(drill 0.508)
			(layers "*.Cu" "*.Mask")
			(remove_unused_layers no)
			(net "GND")
		)
		(pad "I2" thru_hole circle
			(at 2.000001 11.100001 180)
			(size 0.8128 0.8128)
			(drill 0.508)
			(layers "*.Cu" "*.Mask")
			(remove_unused_layers no)
			(net "ETH10G_B1_PRES_N")
		)
		(pad "I3" thru_hole circle
			(at 4 11.2 180)
			(size 0.8128 0.8128)
			(drill 0.508)
			(layers "*.Cu" "*.Mask")
			(remove_unused_layers no)
			(net "P3V3_B1_QSFP")
		)
		(pad "I4" thru_hole circle
			(at 6.000001 11.100001 180)
			(size 0.8128 0.8128)
			(drill 0.508)
			(layers "*.Cu" "*.Mask")
			(remove_unused_layers no)
			(net "SKU_B1_ID1")
		)
		(pad "I5" thru_hole circle
			(at 7.999999 11.2 180)
			(size 0.8128 0.8128)
			(drill 0.508)
			(layers "*.Cu" "*.Mask")
			(remove_unused_layers no)
			(net "BLADE_B1_MATED_N<1>")
		)
		(pad "I6" thru_hole circle
			(at 10 11.100001 180)
			(size 0.8128 0.8128)
			(drill 0.508)
			(layers "*.Cu" "*.Mask")
			(remove_unused_layers no)
			(net "ETH40G_B1_TX0N")
		)
		(pad "J2" thru_hole circle
			(at 2.000001 12.5 180)
			(size 0.8128 0.8128)
			(drill 0.508)
			(layers "*.Cu" "*.Mask")
			(remove_unused_layers no)
			(net "GND")
		)
		(pad "J4" thru_hole circle
			(at 6.000001 12.5 180)
			(size 0.8128 0.8128)
			(drill 0.508)
			(layers "*.Cu" "*.Mask")
			(remove_unused_layers no)
			(net "GND")
		)
		(pad "J6" thru_hole circle
			(at 10 12.5 180)
			(size 0.8128 0.8128)
			(drill 0.508)
			(layers "*.Cu" "*.Mask")
			(remove_unused_layers no)
			(net "GND")
		)
	)
	(footprint ""
		(layer "F.Cu")
		(at -44.958 1.143 180)
		(property "Reference" "FB6"
			(at -2.032 -0.1651 0)
			(unlocked yes)
			(layer "F.SilkS")
			(effects
				(font
					(size 0.762 0.5334)
					(thickness 0.1016)
				)
				(justify left)
			)
		)
		(property "Value" ""
			(at 0 0 180)
			(layer "F.Fab")
			(effects
				(font
					(size 1.27 1.27)
				)
			)
		)
		(duplicate_pad_numbers_are_jumpers no)
		(fp_poly
			(pts
				(xy -1.016 0.508) (xy -1.016 -0.508) (xy 1.016 -0.508) (xy 1.016 0.508)
			)
			(stroke
				(width 0)
				(type default)
			)
			(fill no)
			(layer "F.CrtYd")
		)
		(fp_line
			(start 0.508 0.254)
			(end -0.508 0.254)
			(stroke
				(width 0.1)
				(type default)
			)
			(layer "F.Fab")
		)
		(fp_line
			(start 0.508 -0.254)
			(end 0.508 0.254)
			(stroke
				(width 0.1)
				(type default)
			)
			(layer "F.Fab")
		)
		(fp_line
			(start -0.508 0.254)
			(end -0.508 -0.254)
			(stroke
				(width 0.1)
				(type default)
			)
			(layer "F.Fab")
		)
		(fp_line
			(start -0.508 -0.254)
			(end 0.508 -0.254)
			(stroke
				(width 0.1)
				(type default)
			)
			(layer "F.Fab")
		)
		(pad "1" smd rect
			(at -0.4572 0 270)
			(size 0.508 0.5842)
			(layers "F.Cu" "F.Mask" "F.Paste")
			(net "UNNAMED_8_FERRITE_I54_A")
		)
		(pad "2" smd rect
			(at 0.4572 0 270)
			(size 0.508 0.5842)
			(layers "F.Cu" "F.Mask" "F.Paste")
			(net "P3V3_40G_B2_VCC_RX")
		)
	)
)
